(kicad_pcb
	(version 20260206)
	(generator "pcbnew")
	(generator_version "10.0")
	(general
		(thickness 1.6)
		(legacy_teardrops no)
	)
	(paper "A4")
	(title_block
		(title "03242023_DA0F0TMBIJ0_F0T_Motherboard_J_brd_V01_OCP.brd")
		(comment 1 "Grand Teton / footprints 2857-2863 of 6105")
	)
	(layers
		(0 "F.Cu" signal "TOP")
		(4 "In1.Cu" signal "GND")
		(6 "In2.Cu" signal "IN1")
		(8 "In3.Cu" signal "GND1")
		(10 "In4.Cu" signal "IN2")
		(12 "In5.Cu" signal "GND2")
		(14 "In6.Cu" signal "IN3")
		(16 "In7.Cu" signal "GND3")
		(18 "In8.Cu" signal "VCC")
		(20 "In9.Cu" signal "VCC1")
		(22 "In10.Cu" signal "GND4")
		(24 "In11.Cu" signal "IN4")
		(26 "In12.Cu" signal "GND5")
		(28 "In13.Cu" signal "IN5")
		(30 "In14.Cu" signal "GND6")
		(32 "In15.Cu" signal "IN6")
		(34 "In16.Cu" signal "GND7")
		(2 "B.Cu" signal "BOTTOM")
		(9 "F.Adhes" user "F.Adhesive")
		(11 "B.Adhes" user "B.Adhesive")
		(13 "F.Paste" user "Package Geometry/Pastemask Top")
		(15 "B.Paste" user "Package Geometry/Pastemask Bottom")
		(5 "F.SilkS" user "Ref Des/Silkscreen Top")
		(7 "B.SilkS" user "Ref Des/Silkscreen Bottom")
		(1 "F.Mask" user "Board Geometry/Soldermask Top")
		(3 "B.Mask" user "Board Geometry/Soldermask Bottom")
		(17 "Dwgs.User" user "User.Drawings")
		(19 "Cmts.User" user "User.Comments")
		(21 "Eco1.User" user "User.Eco1")
		(23 "Eco2.User" user "User.Eco2")
		(25 "Edge.Cuts" user "Board Geometry/Outline")
		(27 "Margin" user)
		(31 "F.CrtYd" user "Package Geometry/Place Bound Top")
		(29 "B.CrtYd" user "Package Geometry/Place Bound Bottom")
		(35 "F.Fab" user "Ref Des/Assembly Top")
		(33 "B.Fab" user "Ref Des/Assembly Bottom")
	)
	(footprint ""
		(layer "F.Cu")
		(at 140.70838 -34.994596 180)
		(property "Reference" "R3306"
			(at 0 0 180)
			(layer "F.SilkS")
			(hide yes)
			(effects
				(font
					(size 1.27 1.27)
				)
			)
		)
		(property "Value" ""
			(at 0 0 180)
			(layer "F.Fab")
			(effects
				(font
					(size 1.27 1.27)
				)
			)
		)
		(duplicate_pad_numbers_are_jumpers no)
		(fp_line
			(start 0.7874 0.4064)
			(end -0.7874 0.4064)
			(stroke
				(width 0.1524)
				(type default)
			)
			(layer "F.SilkS")
		)
		(fp_line
			(start 0.7874 -0.4064)
			(end 0.7874 0.4064)
			(stroke
				(width 0.1524)
				(type default)
			)
			(layer "F.SilkS")
		)
		(fp_line
			(start -0.7874 0.4064)
			(end -0.7874 -0.4064)
			(stroke
				(width 0.1524)
				(type default)
			)
			(layer "F.SilkS")
		)
		(fp_line
			(start -0.7874 -0.4064)
			(end 0.7874 -0.4064)
			(stroke
				(width 0.1524)
				(type default)
			)
			(layer "F.SilkS")
		)
		(fp_line
			(start 0.67945 0.3048)
			(end 0.120396 0.3048)
			(stroke
				(width 0.1)
				(type default)
			)
			(layer "F.Fab")
		)
		(fp_line
			(start 0.67945 -0.3048)
			(end 0.67945 0.3048)
			(stroke
				(width 0.1)
				(type default)
			)
			(layer "F.Fab")
		)
		(fp_line
			(start 0.12065 -0.2794)
			(end 0.12065 -0.3048)
			(stroke
				(width 0.1)
				(type default)
			)
			(layer "F.Fab")
		)
		(fp_line
			(start 0.12065 -0.3048)
			(end 0.67945 -0.3048)
			(stroke
				(width 0.1)
				(type default)
			)
			(layer "F.Fab")
		)
		(fp_line
			(start 0.120396 0.3048)
			(end 0.120396 0.2794)
			(stroke
				(width 0.1)
				(type default)
			)
			(layer "F.Fab")
		)
		(fp_line
			(start 0.120396 0.2794)
			(end -0.12065 0.2794)
			(stroke
				(width 0.1)
				(type default)
			)
			(layer "F.Fab")
		)
		(fp_line
			(start -0.12065 0.3048)
			(end -0.67945 0.3048)
			(stroke
				(width 0.1)
				(type default)
			)
			(layer "F.Fab")
		)
		(fp_line
			(start -0.12065 0.2794)
			(end -0.12065 0.3048)
			(stroke
				(width 0.1)
				(type default)
			)
			(layer "F.Fab")
		)
		(fp_line
			(start -0.12065 -0.2794)
			(end 0.12065 -0.2794)
			(stroke
				(width 0.1)
				(type default)
			)
			(layer "F.Fab")
		)
		(fp_line
			(start -0.12065 -0.305054)
			(end -0.12065 -0.2794)
			(stroke
				(width 0.1)
				(type default)
			)
			(layer "F.Fab")
		)
		(fp_line
			(start -0.67945 0.3048)
			(end -0.67945 -0.305054)
			(stroke
				(width 0.1)
				(type default)
			)
			(layer "F.Fab")
		)
		(fp_line
			(start -0.67945 -0.305054)
			(end -0.12065 -0.305054)
			(stroke
				(width 0.1)
				(type default)
			)
			(layer "F.Fab")
		)
		(pad "1" smd circle
			(at -0.40005 0 180)
			(size 0 0)
			(layers "F.Cu" "F.Mask" "F.Paste")
			(net "OCP_V3_2_PRSNT_ALL_R_N")
		)
		(pad "2" smd circle
			(at 0.40005 0 180)
			(size 0 0)
			(layers "F.Cu" "F.Mask" "F.Paste")
			(net "OCP_V3_2_PRSNT_ALL_R3_N")
		)
	)
	(footprint ""
		(layer "F.Cu")
		(at 18.640806 -396.010638 90)
		(property "Reference" "C1870"
			(at 0 0 90)
			(layer "F.SilkS")
			(hide yes)
			(effects
				(font
					(size 1.27 1.27)
				)
			)
		)
		(property "Value" ""
			(at 0 0 90)
			(layer "F.Fab")
			(effects
				(font
					(size 1.27 1.27)
				)
			)
		)
		(duplicate_pad_numbers_are_jumpers no)
		(fp_line
			(start 0.7874 -0.4064)
			(end 0.7874 0.4064)
			(stroke
				(width 0.1524)
				(type default)
			)
			(layer "F.SilkS")
		)
		(fp_line
			(start -0.7874 -0.4064)
			(end 0.7874 -0.4064)
			(stroke
				(width 0.1524)
				(type default)
			)
			(layer "F.SilkS")
		)
		(fp_line
			(start 0.003302 0.4064)
			(end -0.7874 0.4064)
			(stroke
				(width 0.1524)
				(type default)
			)
			(layer "F.SilkS")
		)
		(fp_line
			(start 0.6858 -0.3048)
			(end 0.6858 0.3048)
			(stroke
				(width 0.1)
				(type default)
			)
			(layer "F.Fab")
		)
		(fp_line
			(start 0.1016 -0.3048)
			(end 0.6858 -0.3048)
			(stroke
				(width 0.1)
				(type default)
			)
			(layer "F.Fab")
		)
		(fp_line
			(start -0.1016 -0.3048)
			(end -0.1016 -0.2794)
			(stroke
				(width 0.1)
				(type default)
			)
			(layer "F.Fab")
		)
		(fp_line
			(start -0.6858 -0.3048)
			(end -0.1016 -0.3048)
			(stroke
				(width 0.1)
				(type default)
			)
			(layer "F.Fab")
		)
		(fp_line
			(start 0.1016 -0.2794)
			(end 0.1016 -0.3048)
			(stroke
				(width 0.1)
				(type default)
			)
			(layer "F.Fab")
		)
		(fp_line
			(start -0.1016 -0.2794)
			(end 0.1016 -0.2794)
			(stroke
				(width 0.1)
				(type default)
			)
			(layer "F.Fab")
		)
		(fp_line
			(start 0.1016 0.2794)
			(end -0.1016 0.2794)
			(stroke
				(width 0.1)
				(type default)
			)
			(layer "F.Fab")
		)
		(fp_line
			(start -0.1016 0.2794)
			(end -0.1016 0.3048)
			(stroke
				(width 0.1)
				(type default)
			)
			(layer "F.Fab")
		)
		(fp_line
			(start 0.6858 0.3048)
			(end 0.1016 0.3048)
			(stroke
				(width 0.1)
				(type default)
			)
			(layer "F.Fab")
		)
		(fp_line
			(start 0.1016 0.3048)
			(end 0.1016 0.2794)
			(stroke
				(width 0.1)
				(type default)
			)
			(layer "F.Fab")
		)
		(fp_line
			(start -0.1016 0.3048)
			(end -0.6858 0.3048)
			(stroke
				(width 0.1)
				(type default)
			)
			(layer "F.Fab")
		)
		(fp_line
			(start -0.6858 0.3048)
			(end -0.6858 -0.3048)
			(stroke
				(width 0.1)
				(type default)
			)
			(layer "F.Fab")
		)
		(pad "1" smd rect
			(at -0.40005 0 270)
			(size 0.4572 0.508)
			(layers "F.Cu" "F.Mask" "F.Paste")
			(net "P2E_MB_BMC_TX_BUF_DP<0>")
		)
		(pad "2" smd rect
			(at 0.40005 0 270)
			(size 0.4572 0.508)
			(layers "F.Cu" "F.Mask" "F.Paste")
			(net "P2E_MB_BMC_TX_BUF_C_DP<0>")
		)
	)
	(footprint ""
		(layer "F.Cu")
		(at 74.580496 -70.78599)
		(property "Reference" "D67"
			(at -38.897306 50.178462 90)
			(unlocked yes)
			(layer "F.SilkS")
			(effects
				(font
					(size 0.635 0.4064)
					(thickness 0.1524)
				)
				(justify left)
			)
		)
		(property "Value" ""
			(at 0 0 0)
			(layer "F.Fab")
			(effects
				(font
					(size 1.27 1.27)
				)
			)
		)
		(duplicate_pad_numbers_are_jumpers no)
		(fp_line
			(start -0.90678 0.4826)
			(end -0.90678 -0.4699)
			(stroke
				(width 0.1524)
				(type default)
			)
			(layer "F.SilkS")
		)
		(fp_line
			(start -0.89408 -0.4826)
			(end 0.90678 -0.4826)
			(stroke
				(width 0.1524)
				(type default)
			)
			(layer "F.SilkS")
		)
		(fp_line
			(start -0.79248 -0.4826)
			(end 1.03378 -0.4826)
			(stroke
				(width 0.1524)
				(type default)
			)
			(layer "F.SilkS")
		)
		(fp_line
			(start -0.64008 -0.4826)
			(end 1.16078 -0.4826)
			(stroke
				(width 0.1524)
				(type default)
			)
			(layer "F.SilkS")
		)
		(fp_line
			(start 0.90678 -0.4826)
			(end 0.90678 0.4826)
			(stroke
				(width 0.1524)
				(type default)
			)
			(layer "F.SilkS")
		)
		(fp_line
			(start 0.90678 0.4826)
			(end -0.90678 0.4826)
			(stroke
				(width 0.1524)
				(type default)
			)
			(layer "F.SilkS")
		)
		(fp_line
			(start 1.03378 -0.4826)
			(end 1.03378 0.4826)
			(stroke
				(width 0.1524)
				(type default)
			)
			(layer "F.SilkS")
		)
		(fp_line
			(start 1.03378 0.4826)
			(end -0.79248 0.4826)
			(stroke
				(width 0.1524)
				(type default)
			)
			(layer "F.SilkS")
		)
		(fp_line
			(start 1.16078 -0.4826)
			(end 1.16078 0.4826)
			(stroke
				(width 0.1524)
				(type default)
			)
			(layer "F.SilkS")
		)
		(fp_line
			(start 1.16078 0.4826)
			(end -0.64008 0.4826)
			(stroke
				(width 0.1524)
				(type default)
			)
			(layer "F.SilkS")
		)
		(fp_line
			(start -0.499872 -0.249936)
			(end 0.499872 -0.249936)
			(stroke
				(width 0.1)
				(type default)
			)
			(layer "F.Fab")
		)
		(fp_line
			(start -0.499872 0.249936)
			(end -0.499872 -0.249936)
			(stroke
				(width 0.1)
				(type default)
			)
			(layer "F.Fab")
		)
		(fp_line
			(start 0.499872 -0.249936)
			(end 0.499872 0.249936)
			(stroke
				(width 0.1)
				(type default)
			)
			(layer "F.Fab")
		)
		(fp_line
			(start 0.499872 0.249936)
			(end -0.499872 0.249936)
			(stroke
				(width 0.1)
				(type default)
			)
			(layer "F.Fab")
		)
		(pad "A" smd rect
			(at -0.47498 0)
			(size 0.6096 0.7112)
			(layers "F.Cu" "F.Mask" "F.Paste")
			(net "LED_RST_PLD_CPU0_DRAM_EF_N")
		)
		(pad "C" smd rect
			(at 0.47498 0)
			(size 0.6096 0.7112)
			(layers "F.Cu" "F.Mask" "F.Paste")
			(net "LED_RST_PLD_CPU0_DRAM_EF_N_D")
		)
	)
	(footprint ""
		(layer "F.Cu")
		(at 326.311768 -402.371052 -90)
		(property "Reference" "C1565"
			(at 0 0 270)
			(layer "F.SilkS")
			(hide yes)
			(effects
				(font
					(size 1.27 1.27)
				)
			)
		)
		(property "Value" ""
			(at 0 0 270)
			(layer "F.Fab")
			(effects
				(font
					(size 1.27 1.27)
				)
			)
		)
		(duplicate_pad_numbers_are_jumpers no)
		(fp_line
			(start -0.299974 0.150114)
			(end -0.299974 -0.150114)
			(stroke
				(width 0.1)
				(type default)
			)
			(layer "F.Fab")
		)
		(fp_line
			(start 0.299974 0.150114)
			(end -0.299974 0.150114)
			(stroke
				(width 0.1)
				(type default)
			)
			(layer "F.Fab")
		)
		(fp_line
			(start -0.299974 -0.150114)
			(end 0.299974 -0.150114)
			(stroke
				(width 0.1)
				(type default)
			)
			(layer "F.Fab")
		)
		(fp_line
			(start 0.299974 -0.150114)
			(end 0.299974 0.150114)
			(stroke
				(width 0.1)
				(type default)
			)
			(layer "F.Fab")
		)
		(pad "1" smd rect
			(at -0.2667 0 270)
			(size 0.3048 0.381)
			(layers "F.Cu" "F.Mask" "F.Paste")
			(net "P5E_CPU0_PE4_TX_C_DP<7>")
		)
		(pad "2" smd rect
			(at 0.2667 0 270)
			(size 0.3048 0.381)
			(layers "F.Cu" "F.Mask" "F.Paste")
			(net "P5E_CPU0_PE4_TX_DP<7>")
		)
	)
	(footprint ""
		(layer "F.Cu")
		(at 78.160626 -152.226772 180)
		(property "Reference" "R674"
			(at 0 0 180)
			(layer "F.SilkS")
			(hide yes)
			(effects
				(font
					(size 1.27 1.27)
				)
			)
		)
		(property "Value" ""
			(at 0 0 180)
			(layer "F.Fab")
			(effects
				(font
					(size 1.27 1.27)
				)
			)
		)
		(duplicate_pad_numbers_are_jumpers no)
		(fp_line
			(start 0.7874 0.4064)
			(end -0.7874 0.4064)
			(stroke
				(width 0.1524)
				(type default)
			)
			(layer "F.SilkS")
		)
		(fp_line
			(start 0.7874 -0.4064)
			(end 0.7874 0.4064)
			(stroke
				(width 0.1524)
				(type default)
			)
			(layer "F.SilkS")
		)
		(fp_line
			(start -0.7874 0.4064)
			(end -0.7874 -0.4064)
			(stroke
				(width 0.1524)
				(type default)
			)
			(layer "F.SilkS")
		)
		(fp_line
			(start -0.7874 -0.4064)
			(end 0.7874 -0.4064)
			(stroke
				(width 0.1524)
				(type default)
			)
			(layer "F.SilkS")
		)
		(fp_line
			(start 0.67945 0.3048)
			(end 0.120396 0.3048)
			(stroke
				(width 0.1)
				(type default)
			)
			(layer "F.Fab")
		)
		(fp_line
			(start 0.67945 -0.3048)
			(end 0.67945 0.3048)
			(stroke
				(width 0.1)
				(type default)
			)
			(layer "F.Fab")
		)
		(fp_line
			(start 0.12065 -0.2794)
			(end 0.12065 -0.3048)
			(stroke
				(width 0.1)
				(type default)
			)
			(layer "F.Fab")
		)
		(fp_line
			(start 0.12065 -0.3048)
			(end 0.67945 -0.3048)
			(stroke
				(width 0.1)
				(type default)
			)
			(layer "F.Fab")
		)
		(fp_line
			(start 0.120396 0.3048)
			(end 0.120396 0.2794)
			(stroke
				(width 0.1)
				(type default)
			)
			(layer "F.Fab")
		)
		(fp_line
			(start 0.120396 0.2794)
			(end -0.12065 0.2794)
			(stroke
				(width 0.1)
				(type default)
			)
			(layer "F.Fab")
		)
		(fp_line
			(start -0.12065 0.3048)
			(end -0.67945 0.3048)
			(stroke
				(width 0.1)
				(type default)
			)
			(layer "F.Fab")
		)
		(fp_line
			(start -0.12065 0.2794)
			(end -0.12065 0.3048)
			(stroke
				(width 0.1)
				(type default)
			)
			(layer "F.Fab")
		)
		(fp_line
			(start -0.12065 -0.2794)
			(end 0.12065 -0.2794)
			(stroke
				(width 0.1)
				(type default)
			)
			(layer "F.Fab")
		)
		(fp_line
			(start -0.12065 -0.305054)
			(end -0.12065 -0.2794)
			(stroke
				(width 0.1)
				(type default)
			)
			(layer "F.Fab")
		)
		(fp_line
			(start -0.67945 0.3048)
			(end -0.67945 -0.305054)
			(stroke
				(width 0.1)
				(type default)
			)
			(layer "F.Fab")
		)
		(fp_line
			(start -0.67945 -0.305054)
			(end -0.12065 -0.305054)
			(stroke
				(width 0.1)
				(type default)
			)
			(layer "F.Fab")
		)
		(pad "1" smd circle
			(at -0.40005 0 180)
			(size 0 0)
			(layers "F.Cu" "F.Mask" "F.Paste")
			(net "I3C_SPD_DDRABCD_CPU1_LVC1_R_SCL")
		)
		(pad "2" smd circle
			(at 0.40005 0 180)
			(size 0 0)
			(layers "F.Cu" "F.Mask" "F.Paste")
			(net "I3C_SPD_DDRABCD_CPU1_LVC1_SCL")
		)
	)
	(footprint ""
		(layer "F.Cu")
		(at 208.49336 -119.1006 180)
		(property "Reference" "R4719"
			(at 0 0 180)
			(layer "F.SilkS")
			(hide yes)
			(effects
				(font
					(size 1.27 1.27)
				)
			)
		)
		(property "Value" ""
			(at 0 0 180)
			(layer "F.Fab")
			(effects
				(font
					(size 1.27 1.27)
				)
			)
		)
		(duplicate_pad_numbers_are_jumpers no)
		(fp_line
			(start 0.7874 0.4064)
			(end -0.7874 0.4064)
			(stroke
				(width 0.1524)
				(type default)
			)
			(layer "F.SilkS")
		)
		(fp_line
			(start 0.7874 -0.4064)
			(end 0.7874 0.4064)
			(stroke
				(width 0.1524)
				(type default)
			)
			(layer "F.SilkS")
		)
		(fp_line
			(start -0.7874 0.4064)
			(end -0.7874 -0.4064)
			(stroke
				(width 0.1524)
				(type default)
			)
			(layer "F.SilkS")
		)
		(fp_line
			(start -0.7874 -0.4064)
			(end 0.7874 -0.4064)
			(stroke
				(width 0.1524)
				(type default)
			)
			(layer "F.SilkS")
		)
		(fp_line
			(start 0.67945 0.3048)
			(end 0.120396 0.3048)
			(stroke
				(width 0.1)
				(type default)
			)
			(layer "F.Fab")
		)
		(fp_line
			(start 0.67945 -0.3048)
			(end 0.67945 0.3048)
			(stroke
				(width 0.1)
				(type default)
			)
			(layer "F.Fab")
		)
		(fp_line
			(start 0.12065 -0.2794)
			(end 0.12065 -0.3048)
			(stroke
				(width 0.1)
				(type default)
			)
			(layer "F.Fab")
		)
		(fp_line
			(start 0.12065 -0.3048)
			(end 0.67945 -0.3048)
			(stroke
				(width 0.1)
				(type default)
			)
			(layer "F.Fab")
		)
		(fp_line
			(start 0.120396 0.3048)
			(end 0.120396 0.2794)
			(stroke
				(width 0.1)
				(type default)
			)
			(layer "F.Fab")
		)
		(fp_line
			(start 0.120396 0.2794)
			(end -0.12065 0.2794)
			(stroke
				(width 0.1)
				(type default)
			)
			(layer "F.Fab")
		)
		(fp_line
			(start -0.12065 0.3048)
			(end -0.67945 0.3048)
			(stroke
				(width 0.1)
				(type default)
			)
			(layer "F.Fab")
		)
		(fp_line
			(start -0.12065 0.2794)
			(end -0.12065 0.3048)
			(stroke
				(width 0.1)
				(type default)
			)
			(layer "F.Fab")
		)
		(fp_line
			(start -0.12065 -0.2794)
			(end 0.12065 -0.2794)
			(stroke
				(width 0.1)
				(type default)
			)
			(layer "F.Fab")
		)
		(fp_line
			(start -0.12065 -0.305054)
			(end -0.12065 -0.2794)
			(stroke
				(width 0.1)
				(type default)
			)
			(layer "F.Fab")
		)
		(fp_line
			(start -0.67945 0.3048)
			(end -0.67945 -0.305054)
			(stroke
				(width 0.1)
				(type default)
			)
			(layer "F.Fab")
		)
		(fp_line
			(start -0.67945 -0.305054)
			(end -0.12065 -0.305054)
			(stroke
				(width 0.1)
				(type default)
			)
			(layer "F.Fab")
		)
		(pad "1" smd circle
			(at -0.40005 0 180)
			(size 0 0)
			(layers "F.Cu" "F.Mask" "F.Paste")
			(net "P3V3_AUX")
		)
		(pad "2" smd circle
			(at 0.40005 0 180)
			(size 0 0)
			(layers "F.Cu" "F.Mask" "F.Paste")
			(net "FM_AC_PWR_BTN_PLD_ISO_N")
		)
	)
	(footprint ""
		(layer "F.Cu")
		(at 21.096478 -16.099536 90)
		(property "Reference" "C811"
			(at 0 0 90)
			(layer "F.SilkS")
			(hide yes)
			(effects
				(font
					(size 1.27 1.27)
				)
			)
		)
		(property "Value" ""
			(at 0 0 90)
			(layer "F.Fab")
			(effects
				(font
					(size 1.27 1.27)
				)
			)
		)
		(duplicate_pad_numbers_are_jumpers no)
		(fp_line
			(start 0.299974 -0.150114)
			(end 0.299974 0.150114)
			(stroke
				(width 0.1)
				(type default)
			)
			(layer "F.Fab")
		)
		(fp_line
			(start -0.299974 -0.150114)
			(end 0.299974 -0.150114)
			(stroke
				(width 0.1)
				(type default)
			)
			(layer "F.Fab")
		)
		(fp_line
			(start 0.299974 0.150114)
			(end -0.299974 0.150114)
			(stroke
				(width 0.1)
				(type default)
			)
			(layer "F.Fab")
		)
		(fp_line
			(start -0.299974 0.150114)
			(end -0.299974 -0.150114)
			(stroke
				(width 0.1)
				(type default)
			)
			(layer "F.Fab")
		)
		(pad "1" smd rect
			(at -0.2667 0 90)
			(size 0.3048 0.381)
			(layers "F.Cu" "F.Mask" "F.Paste")
			(net "P5E_CPU1_PE1_TX_C_DP<13>")
		)
		(pad "2" smd rect
			(at 0.2667 0 90)
			(size 0.3048 0.381)
			(layers "F.Cu" "F.Mask" "F.Paste")
			(net "P5E_CPU1_PE1_TX_DP<13>")
		)
	)
)
